FILE_TYPE = CONNECTIVITY;
{Allegro Design Entry HDL 16.6-p007 (v16-6-112F) 10/10/2012}
"PAGE_NUMBER" = 162;
0"NC";
1"P3V3_STBY\g";
2"GND\g";
3"GND\g";
4"GND\g";
5"SPI_BMC_BT_DI";
6"SPI_BMC_BT_DO";
7"PU_SPI_BMC_BT_HOLD_N";
8"PU_SPI_BMC_BT_WP_N";
9"SPI_BMC_BT_CS_N";
10"SPI_BMC_BT_CLK";
11"SPI_BMC_BT_DI_R";
12"PU_SPI_FLASH_RESET_2_N";
13"TP_SPI_2_3";
14"TP_SPI_2_4";
15"TP_SPI_2_6";
16"TP_SPI_2_5";
17"TP_SPI_2_2";
18"TP_SPI_2_1";
19"TP_SPI_2_0";
%"P3V3_STBY"
"1","(4900,3725)","0","mstr_symbols","I10";
;
VOLTAGE"3.3V"
CDS_LIB"mstr_symbols"
SIZE"1B"
BODY_TYPE"PLUMBING"
HDL_POWER"P3V3_STBY";
"G\NAC"1;
%"RES"
"1","(5075,2550)","0","mstr_discrete","I13";
;
CDS_SEC"1"
TOLERANCE"1%"
PACK_TYPE"0402"
MATERIAL"CHIP"
BOM_COST"SM_MEM"
ROOM"BMC_BOOT_SPI"
SEC"1"
SEC_TYPE"0402"
PART_NUMBER"G21796-074"
CDS_LIB"mstr_discrete"
CDS_LOCATION"R8F12"
WATTAGE"1/16W"
VALUE"33.2"
LOCATION"R8F12";
"B"
$PN"2"11;
"A"
$PN"1"5;
%"RES"
"2","(4825,3325)","2","mstr_discrete","I22";
;
BOM_COST"SM_MEM"
CDS_SEC"1"
$SEC"1"
ROOM"BMC_BOOT_SPI"
CDS_LOCATION"R8F34"
CDS_LIB"mstr_discrete"
LOCATION"R8F34"
MATERIAL"CHIP"
VALUE"4.75K"
WATTAGE"1/16W"
TOLERANCE"1%"
PACK_TYPE"0402"
PART_NUMBER"G21796-072";
"A"
$PN"1"1;
"B"
$PN"2"8;
%"RES"
"2","(4550,3325)","2","mstr_discrete","I23";
;
$SEC"1"
CDS_SEC"1"
BOM_COST"SM_MEM"
CDS_LOCATION"R8F13"
ROOM"BMC_BOOT_SPI"
CDS_LIB"mstr_discrete"
VALUE"4.75K"
MATERIAL"CHIP"
LOCATION"R8F13"
WATTAGE"1/16W"
TOLERANCE"1%"
PACK_TYPE"0402"
PART_NUMBER"G21796-072";
"A"
$PN"1"1;
"B"
$PN"2"9;
%"RES"
"2","(4875,2050)","0","mstr_discrete","I24";
;
BOM_COST"SM_MEM"
CDS_SEC"1"
$SEC"1"
ROOM"BMC_BOOT_SPI"
CDS_LOCATION"R8F35"
CDS_LIB"mstr_discrete"
LOCATION"R8F35"
VALUE"1.00K"
TOLERANCE"1%"
WATTAGE"1/16W"
PART_NUMBER"G21796-026"
MATERIAL"EMPTY"
PACK_TYPE"0402";
"A"
$PN"1"8;
"B"
$PN"2"3;
%"CAP_A"
"1","(7650,3400)","0","dev_discrete","I28";
;
BOM_COST"SM_MEM"
$SEC"1"
CDS_SEC"1"
ROOM"BMC_BOOT_SPI"
CDS_LOCATION"C8F5"
CDS_LIB"dev_discrete"
VOLTAGE"25V"
PACK_TYPE"0402V"
TOLERANCE"10%"
VALUE"0.01UF"
PART_NUMBER"A36096-045"
LOCATION"C8F5"
MATERIAL"X7R";
"B"
$PN"2"2;
"A"
$PN"1"1;
%"CAP_A"
"1","(7350,3400)","0","dev_discrete","I30";
;
BOM_COST"SM_MEM"
CDS_SEC"1"
$SEC"1"
ROOM"BMC_BOOT_SPI"
CDS_LOCATION"C8F4"
CDS_LIB"dev_discrete"
PART_NUMBER"D97712-004"
LOCATION"C8F4"
VALUE"1.0UF"
TOLERANCE"10%"
PACK_TYPE"0402V"
VOLTAGE"6.3V"
MATERIAL"X6S";
"B"
$PN"2"2;
"A"
$PN"1"1;
%"GND"
"1","(7650,3075)","0","mstr_symbols","I31";
;
HDL_POWER"GND"
CDS_LIB"mstr_symbols"
SIZE"1B"
BODY_TYPE"PLUMBING"
VOLTAGE"0.0V";
"A\NAC"2;
%"W25Q128"
"3","(6450,2800)","0","mstr_memory","I32";
;
CDS_SEC"1"
CDS_LIB"mstr_memory"
CDS_LMAN_SYM_OUTLINE"-500,325,500,-325"
PACK_TYPE"SKT16"
SEC_TYPE"SKT16"
BOM_COST"SM_MEM"
SEC"1"
CDS_LOCATION"U8F2"
ROOM"BMC_BOOT_SPI"
PART_NUMBER"H12709-001"
LOCATION"U8F2"
MATERIAL"IC";
"DI_IO<0>"
$PN"15"6;
"WP_N_IO<2> \B"
$PN"9"8;
"VCC"
$PN"2"1;
"NC<6>"
$PN"14"15;
"NC<5>"
$PN"13"16;
"NC<4>"
$PN"12"14;
"NC<3>"
$PN"11"13;
"GND"
$PN"10"4;
"NC<2>"
$PN"6"17;
"NC<1>"
$PN"5"18;
"NC<0>"
$PN"4"19;
"DO_IO<1>"
$PN"8"11;
"HOLD_N_IO<3> \B"
$PN"1"7;
"CS_N \B"
$PN"7"9;
"CLK"
$PN"16"10;
"RESET_N \B"
$PN"3"12;
%"GND"
"1","(4875,1750)","0","mstr_symbols","I33";
;
HDL_POWER"GND"
SIZE"1B"
CDS_LIB"mstr_symbols"
VOLTAGE"0.0V"
BODY_TYPE"PLUMBING";
"A\NAC"3;
%"GND"
"1","(7100,2350)","0","mstr_symbols","I6";
;
SIZE"1B"
HDL_POWER"GND"
BODY_TYPE"PLUMBING"
CDS_LIB"mstr_symbols"
VOLTAGE"0";
"A\NAC"4;
%"RES"
"2","(5300,3300)","0","mstr_discrete","I8";
;
CDS_SEC"1"
SEC_TYPE"0402"
BOM_COST"SM_MEM"
SEC"1"
ROOM"BMC_BOOT_SPI"
CDS_LOCATION"R8F16"
CDS_LIB"mstr_discrete"
VALUE"4.75K"
TOLERANCE"1%"
MATERIAL"EMPTY"
LOCATION"R8F16"
PACK_TYPE"0402"
WATTAGE"1/16W"
PART_NUMBER"G21796-072";
"A"
$PN"1"1;
"B"
$PN"2"12;
%"RES"
"2","(5100,3325)","2","mstr_discrete","I9";
;
CDS_SEC"1"
SEC_TYPE"0402"
BOM_COST"SM_MEM"
ROOM"BMC_BOOT_SPI"
SEC"1"
CDS_LOCATION"R8F14"
CDS_LIB"mstr_discrete"
MATERIAL"CHIP"
LOCATION"R8F14"
VALUE"4.75K"
PACK_TYPE"0402"
TOLERANCE"1%"
WATTAGE"1/16W"
PART_NUMBER"G21796-072";
"A"
$PN"1"1;
"B"
$PN"2"7;
END.
